G04*
G04 #@! TF.GenerationSoftware,Altium Limited,Altium Designer,22.4.2 (48)*
G04*
G04 Layer_Color=32768*
%FSLAX25Y25*%
%MOIN*%
G70*
G04*
G04 #@! TF.SameCoordinates,446674BB-F454-490D-8607-5140536C8ADF*
G04*
G04*
G04 #@! TF.FilePolarity,Positive*
G04*
G01*
G75*
%ADD14C,0.00394*%
D14*
X670866Y-227559D02*
X674803D01*
X672835Y-229528D02*
Y-225591D01*
X670866Y-276772D02*
X674803D01*
X672835Y-278740D02*
Y-274803D01*
X38386Y11811D02*
X42323D01*
X40354Y9843D02*
Y13780D01*
X31496Y11811D02*
X35433D01*
X33465Y9843D02*
Y13780D01*
X24606Y11811D02*
X28543D01*
X26575Y9843D02*
Y13780D01*
X45276Y11811D02*
X49213D01*
X47244Y9843D02*
Y13780D01*
X80709Y-113189D02*
X84646D01*
X82677Y-115157D02*
Y-111221D01*
X73819Y-125394D02*
X77756D01*
X75787Y-127362D02*
Y-123425D01*
X647638Y-60876D02*
Y-56939D01*
X645669Y-58907D02*
X649606D01*
X613189Y-23474D02*
Y-19537D01*
X611221Y-21506D02*
X615158D01*
X87598Y-94340D02*
X91535D01*
X89567Y-96309D02*
Y-92372D01*
X121063Y-76033D02*
X125000D01*
X123031Y-78002D02*
Y-74065D01*
X484252Y-124852D02*
X488189D01*
X486221Y-126821D02*
Y-122883D01*
X513779Y-124852D02*
X517717D01*
X515748Y-126821D02*
Y-122883D01*
X458661Y-125836D02*
X462598D01*
X460630Y-127805D02*
Y-123868D01*
M02*
